(kicad_pcb
	(version 20260206)
	(generator "pcbnew")
	(generator_version "10.0")
	(general
		(thickness 1.6)
		(legacy_teardrops no)
	)
	(paper "A4")
	(title_block
		(title "04192023_DAF0TMB3IC0_F0TG_MB_C_brd_V02_OCP.brd")
		(comment 1 "Grand Teton / footprint 4641 of 8354 (U6012), pads 224-336 of 354")
	)
	(layers
		(0 "F.Cu" signal "TOP")
		(4 "In1.Cu" signal "GND")
		(6 "In2.Cu" signal "IN1")
		(8 "In3.Cu" signal "GND1")
		(10 "In4.Cu" signal "IN2")
		(12 "In5.Cu" signal "GND2")
		(14 "In6.Cu" signal "IN3")
		(16 "In7.Cu" signal "GND3")
		(18 "In8.Cu" signal "VCC")
		(20 "In9.Cu" signal "VCC1")
		(22 "In10.Cu" signal "GND4")
		(24 "In11.Cu" signal "IN4")
		(26 "In12.Cu" signal "GND5")
		(28 "In13.Cu" signal "IN5")
		(30 "In14.Cu" signal "GND6")
		(32 "In15.Cu" signal "IN6")
		(34 "In16.Cu" signal "GND7")
		(2 "B.Cu" signal "BOTTOM")
		(9 "F.Adhes" user "F.Adhesive")
		(11 "B.Adhes" user "B.Adhesive")
		(13 "F.Paste" user "Package Geometry/Pastemask Top")
		(15 "B.Paste" user "Package Geometry/Pastemask Bottom")
		(5 "F.SilkS" user "Ref Des/Silkscreen Top")
		(7 "B.SilkS" user "Ref Des/Silkscreen Bottom")
		(1 "F.Mask" user "Board Geometry/Soldermask Top")
		(3 "B.Mask" user "Board Geometry/Soldermask Bottom")
		(17 "Dwgs.User" user "User.Drawings")
		(19 "Cmts.User" user "User.Comments")
		(21 "Eco1.User" user "User.Eco1")
		(23 "Eco2.User" user "User.Eco2")
		(25 "Edge.Cuts" user "Board Geometry/Outline")
		(27 "Margin" user)
		(31 "F.CrtYd" user "Package Geometry/Place Bound Top")
		(29 "B.CrtYd" user "Package Geometry/Place Bound Bottom")
		(35 "F.Fab" user "Ref Des/Assembly Top")
		(33 "B.Fab" user "Ref Des/Assembly Bottom")
	)
	(footprint ""
		(layer "F.Cu")
		(at 412.095696 -395.724634)
		(property "Reference" "U6012"
			(at -8.00862 -7.649972 0)
			(unlocked yes)
			(layer "F.SilkS")
			(effects
				(font
					(size 0.7874 0.5842)
					(thickness 0.1524)
				)
				(justify left)
			)
		)
		(property "Value" ""
			(at 0 0 0)
			(layer "F.Fab")
			(effects
				(font
					(size 1.27 1.27)
				)
			)
		)
		(duplicate_pad_numbers_are_jumpers no)
		(pad "DY32" smd circle
			(at -5.997448 2.724912)
			(size 0.381 0.381)
			(layers "F.Cu" "F.Mask" "F.Paste")
			(net "GND")
		)
		(pad "E8" smd circle
			(at 10.366502 -1.988312)
			(size 0.3048 0.3048)
			(layers "F.Cu" "F.Mask" "F.Paste")
			(net "JTAG_TRST_RT_CPU0_P2_N")
		)
		(pad "E11" smd circle
			(at 10.366502 -1.388364)
			(size 0.3048 0.3048)
			(layers "F.Cu" "F.Mask" "F.Paste")
			(net "RXDET_BYP_RT_CPU0_P2")
		)
		(pad "E14" smd circle
			(at 10.366502 -0.788416)
			(size 0.3048 0.3048)
			(layers "F.Cu" "F.Mask" "F.Paste")
			(net "GND")
		)
		(pad "E18" smd circle
			(at 10.366502 -0.188468)
			(size 0.3048 0.3048)
			(layers "F.Cu" "F.Mask" "F.Paste")
			(net "Net_2210")
		)
		(pad "E27" smd circle
			(at 10.366502 1.61163)
			(size 0.3048 0.3048)
			(layers "F.Cu" "F.Mask" "F.Paste")
			(net "GND")
		)
		(pad "E30" smd circle
			(at 10.366502 2.211578)
			(size 0.3048 0.3048)
			(layers "F.Cu" "F.Mask" "F.Paste")
			(net "GND")
		)
		(pad "E33" smd circle
			(at 10.366502 2.811526)
			(size 0.3048 0.3048)
			(layers "F.Cu" "F.Mask" "F.Paste")
			(net "GND")
		)
		(pad "EA2" smd circle
			(at -6.050026 -3.41884)
			(size 0.3048 0.3048)
			(layers "F.Cu" "F.Mask" "F.Paste")
			(net "GND")
		)
		(pad "EA34" smd circle
			(at -6.050026 3.420364)
			(size 0.3048 0.3048)
			(layers "F.Cu" "F.Mask" "F.Paste")
			(net "GND")
		)
		(pad "EB1" smd oval
			(at -6.35 -3.938524)
			(size 0.254 0.3302)
			(layers "F.Cu" "F.Mask" "F.Paste")
			(net "GND")
		)
		(pad "EB35" smd oval
			(at -6.35 3.940048)
			(size 0.254 0.3302)
			(layers "F.Cu" "F.Mask" "F.Paste")
			(net "GND")
		)
		(pad "EC7" smd circle
			(at -6.397498 -2.12471)
			(size 0.381 0.381)
			(layers "F.Cu" "F.Mask" "F.Paste")
			(net "P5E_CPU0_P2_TX_BUF_DP<2>")
		)
		(pad "EC26" smd circle
			(at -6.397498 1.339342)
			(size 0.381 0.381)
			(layers "F.Cu" "F.Mask" "F.Paste")
			(net "P5E_CPU0_P2_RX_DP<2>")
		)
		(pad "ED2" smd circle
			(at -6.649974 -3.41884)
			(size 0.3048 0.3048)
			(layers "F.Cu" "F.Mask" "F.Paste")
			(net "P5E_CPU0_P2_RX_BUF_DN<2>")
		)
		(pad "ED34" smd circle
			(at -6.649974 3.420364)
			(size 0.3048 0.3048)
			(layers "F.Cu" "F.Mask" "F.Paste")
			(net "P5E_CPU0_P2_TX_C_DN<2>")
		)
		(pad "EE10" smd circle
			(at -6.797294 -1.431798)
			(size 0.381 0.381)
			(layers "F.Cu" "F.Mask" "F.Paste")
			(net "P5E_CPU0_P2_TX_BUF_DN<2>")
		)
		(pad "EE29" smd circle
			(at -6.797294 2.032254)
			(size 0.381 0.381)
			(layers "F.Cu" "F.Mask" "F.Paste")
			(net "P5E_CPU0_P2_RX_DN<2>")
		)
		(pad "EF1" smd oval
			(at -6.949948 -3.938524)
			(size 0.254 0.3302)
			(layers "F.Cu" "F.Mask" "F.Paste")
			(net "P5E_CPU0_P2_RX_BUF_DP<2>")
		)
		(pad "EF35" smd oval
			(at -6.949948 3.940048)
			(size 0.254 0.3302)
			(layers "F.Cu" "F.Mask" "F.Paste")
			(net "P5E_CPU0_P2_TX_C_DP<2>")
		)
		(pad "EG4" smd circle
			(at -7.197344 -2.817368)
			(size 0.381 0.381)
			(layers "F.Cu" "F.Mask" "F.Paste")
			(net "GND")
		)
		(pad "EG13" smd circle
			(at -7.197344 -0.79629)
			(size 0.3048 0.3048)
			(layers "F.Cu" "F.Mask" "F.Paste")
			(net "GND")
		)
		(pad "EG17" smd circle
			(at -7.197344 -0.296164)
			(size 0.3048 0.3048)
			(layers "F.Cu" "F.Mask" "F.Paste")
			(net "P0V9_CPU0_RT2_2A")
		)
		(pad "EG20" smd circle
			(at -7.197344 0.203708)
			(size 0.3048 0.3048)
			(layers "F.Cu" "F.Mask" "F.Paste")
			(net "P0V9_CPU0_RT2_2A")
		)
		(pad "EG22" smd circle
			(at -7.197344 0.703834)
			(size 0.3048 0.3048)
			(layers "F.Cu" "F.Mask" "F.Paste")
			(net "GND")
		)
		(pad "EG32" smd circle
			(at -7.197344 2.724912)
			(size 0.381 0.381)
			(layers "F.Cu" "F.Mask" "F.Paste")
			(net "GND")
		)
		(pad "EH2" smd circle
			(at -7.249922 -3.41884)
			(size 0.3048 0.3048)
			(layers "F.Cu" "F.Mask" "F.Paste")
			(net "GND")
		)
		(pad "EH34" smd circle
			(at -7.249922 3.420364)
			(size 0.3048 0.3048)
			(layers "F.Cu" "F.Mask" "F.Paste")
			(net "GND")
		)
		(pad "EJ1" smd oval
			(at -7.549896 -3.938524)
			(size 0.254 0.3302)
			(layers "F.Cu" "F.Mask" "F.Paste")
			(net "GND")
		)
		(pad "EJ35" smd oval
			(at -7.549896 3.940048)
			(size 0.254 0.3302)
			(layers "F.Cu" "F.Mask" "F.Paste")
			(net "GND")
		)
		(pad "EK7" smd circle
			(at -7.597394 -2.12471)
			(size 0.381 0.381)
			(layers "F.Cu" "F.Mask" "F.Paste")
			(net "P5E_CPU0_P2_TX_BUF_DP<1>")
		)
		(pad "EK26" smd circle
			(at -7.597394 1.339342)
			(size 0.381 0.381)
			(layers "F.Cu" "F.Mask" "F.Paste")
			(net "P5E_CPU0_P2_RX_DP<1>")
		)
		(pad "EL2" smd circle
			(at -7.850124 -3.41884)
			(size 0.3048 0.3048)
			(layers "F.Cu" "F.Mask" "F.Paste")
			(net "P5E_CPU0_P2_RX_BUF_DN<1>")
		)
		(pad "EL34" smd circle
			(at -7.850124 3.420364)
			(size 0.3048 0.3048)
			(layers "F.Cu" "F.Mask" "F.Paste")
			(net "P5E_CPU0_P2_TX_C_DP<1>")
		)
		(pad "EM10" smd circle
			(at -7.997444 -1.431798)
			(size 0.381 0.381)
			(layers "F.Cu" "F.Mask" "F.Paste")
			(net "P5E_CPU0_P2_TX_BUF_DN<1>")
		)
		(pad "EM29" smd circle
			(at -7.997444 2.032254)
			(size 0.381 0.381)
			(layers "F.Cu" "F.Mask" "F.Paste")
			(net "P5E_CPU0_P2_RX_DN<1>")
		)
		(pad "EN1" smd oval
			(at -8.150098 -3.938524)
			(size 0.254 0.3302)
			(layers "F.Cu" "F.Mask" "F.Paste")
			(net "P5E_CPU0_P2_RX_BUF_DP<1>")
		)
		(pad "EN35" smd oval
			(at -8.150098 3.940048)
			(size 0.254 0.3302)
			(layers "F.Cu" "F.Mask" "F.Paste")
			(net "P5E_CPU0_P2_TX_C_DN<1>")
		)
		(pad "EP4" smd circle
			(at -8.397494 -2.817368)
			(size 0.381 0.381)
			(layers "F.Cu" "F.Mask" "F.Paste")
			(net "GND")
		)
		(pad "EP13" smd circle
			(at -8.397494 -0.79629)
			(size 0.3048 0.3048)
			(layers "F.Cu" "F.Mask" "F.Paste")
			(net "GND")
		)
		(pad "EP17" smd circle
			(at -8.397494 -0.296164)
			(size 0.3048 0.3048)
			(layers "F.Cu" "F.Mask" "F.Paste")
			(net "P0V9_CPU0_RT2_2A")
		)
		(pad "EP20" smd circle
			(at -8.397494 0.203708)
			(size 0.3048 0.3048)
			(layers "F.Cu" "F.Mask" "F.Paste")
			(net "P0V9_CPU0_RT2_2A")
		)
		(pad "EP22" smd circle
			(at -8.397494 0.703834)
			(size 0.3048 0.3048)
			(layers "F.Cu" "F.Mask" "F.Paste")
			(net "GND")
		)
		(pad "EP32" smd circle
			(at -8.397494 2.724912)
			(size 0.381 0.381)
			(layers "F.Cu" "F.Mask" "F.Paste")
			(net "GND")
		)
		(pad "ER2" smd circle
			(at -8.450072 -3.41884)
			(size 0.3048 0.3048)
			(layers "F.Cu" "F.Mask" "F.Paste")
			(net "GND")
		)
		(pad "ER34" smd circle
			(at -8.450072 3.420364)
			(size 0.3048 0.3048)
			(layers "F.Cu" "F.Mask" "F.Paste")
			(net "GND")
		)
		(pad "ET1" smd oval
			(at -8.750046 -3.938524)
			(size 0.254 0.3302)
			(layers "F.Cu" "F.Mask" "F.Paste")
			(net "GND")
		)
		(pad "ET35" smd oval
			(at -8.750046 3.940048)
			(size 0.254 0.3302)
			(layers "F.Cu" "F.Mask" "F.Paste")
			(net "GND")
		)
		(pad "EU7" smd circle
			(at -8.79729 -2.12471)
			(size 0.381 0.381)
			(layers "F.Cu" "F.Mask" "F.Paste")
			(net "P5E_CPU0_P2_TX_BUF_DP<0>")
		)
		(pad "EU26" smd circle
			(at -8.79729 1.339342)
			(size 0.381 0.381)
			(layers "F.Cu" "F.Mask" "F.Paste")
			(net "P5E_CPU0_P2_RX_DP<0>")
		)
		(pad "EV2" smd circle
			(at -9.05002 -3.41884)
			(size 0.3048 0.3048)
			(layers "F.Cu" "F.Mask" "F.Paste")
			(net "P5E_CPU0_P2_RX_BUF_DN<0>")
		)
		(pad "EV34" smd circle
			(at -9.05002 3.420364)
			(size 0.3048 0.3048)
			(layers "F.Cu" "F.Mask" "F.Paste")
			(net "P5E_CPU0_P2_TX_C_DN<0>")
		)
		(pad "EW10" smd circle
			(at -9.19734 -1.431798)
			(size 0.381 0.381)
			(layers "F.Cu" "F.Mask" "F.Paste")
			(net "P5E_CPU0_P2_TX_BUF_DN<0>")
		)
		(pad "EW29" smd circle
			(at -9.19734 2.032254)
			(size 0.381 0.381)
			(layers "F.Cu" "F.Mask" "F.Paste")
			(net "P5E_CPU0_P2_RX_DN<0>")
		)
		(pad "EY1" smd oval
			(at -9.349994 -3.938524)
			(size 0.254 0.3302)
			(layers "F.Cu" "F.Mask" "F.Paste")
			(net "P5E_CPU0_P2_RX_BUF_DP<0>")
		)
		(pad "EY35" smd oval
			(at -9.349994 3.940048)
			(size 0.254 0.3302)
			(layers "F.Cu" "F.Mask" "F.Paste")
			(net "P5E_CPU0_P2_TX_C_DP<0>")
		)
		(pad "F2" smd circle
			(at 10.150094 -3.41884)
			(size 0.3048 0.3048)
			(layers "F.Cu" "F.Mask" "F.Paste")
			(net "RST_RT_CPU0_P2_PERST_N")
		)
		(pad "F34" smd circle
			(at 10.150094 3.420364)
			(size 0.3048 0.3048)
			(layers "F.Cu" "F.Mask" "F.Paste")
			(net "RT_CPU0_P2_ADDR1")
		)
		(pad "FA15" smd circle
			(at -9.59739 -0.738886)
			(size 0.381 0.381)
			(layers "F.Cu" "F.Mask" "F.Paste")
			(net "GND")
		)
		(pad "FA32" smd circle
			(at -9.59739 2.724912)
			(size 0.381 0.381)
			(layers "F.Cu" "F.Mask" "F.Paste")
			(net "GND")
		)
		(pad "FB2" smd circle
			(at -9.649968 -3.41884)
			(size 0.3048 0.3048)
			(layers "F.Cu" "F.Mask" "F.Paste")
			(net "GND")
		)
		(pad "FB34" smd circle
			(at -9.649968 3.420364)
			(size 0.3048 0.3048)
			(layers "F.Cu" "F.Mask" "F.Paste")
			(net "GND")
		)
		(pad "FC3" smd circle
			(at -9.846818 -2.888488)
			(size 0.3048 0.3048)
			(layers "F.Cu" "F.Mask" "F.Paste")
			(net "GND")
		)
		(pad "FC6" smd circle
			(at -9.846818 -2.288286)
			(size 0.3048 0.3048)
			(layers "F.Cu" "F.Mask" "F.Paste")
			(net "GND")
		)
		(pad "FC9" smd circle
			(at -9.846818 -1.688338)
			(size 0.3048 0.3048)
			(layers "F.Cu" "F.Mask" "F.Paste")
			(net "GND")
		)
		(pad "FC19" smd circle
			(at -9.846818 0.111506)
			(size 0.3048 0.3048)
			(layers "F.Cu" "F.Mask" "F.Paste")
			(net "GND")
		)
		(pad "FC23" smd circle
			(at -9.846818 0.711708)
			(size 0.3048 0.3048)
			(layers "F.Cu" "F.Mask" "F.Paste")
			(net "GND")
		)
		(pad "FC25" smd circle
			(at -9.846818 1.311656)
			(size 0.3048 0.3048)
			(layers "F.Cu" "F.Mask" "F.Paste")
			(net "GND")
		)
		(pad "FC28" smd circle
			(at -9.846818 1.911604)
			(size 0.3048 0.3048)
			(layers "F.Cu" "F.Mask" "F.Paste")
			(net "GND")
		)
		(pad "FD1" smd oval
			(at -9.949942 -3.938524)
			(size 0.254 0.3302)
			(layers "F.Cu" "F.Mask" "F.Paste")
			(net "GND")
		)
		(pad "FD35" smd oval
			(at -9.949942 3.940048)
			(size 0.254 0.3302)
			(layers "F.Cu" "F.Mask" "F.Paste")
			(net "GND")
		)
		(pad "FE2" smd circle
			(at -10.249916 -3.41884)
			(size 0.3048 0.3048)
			(layers "F.Cu" "F.Mask" "F.Paste")
			(net "NCF_CPU0_P2_GND")
		)
		(pad "FE34" smd circle
			(at -10.249916 3.420364)
			(size 0.3048 0.3048)
			(layers "F.Cu" "F.Mask" "F.Paste")
			(net "NCF_CPU0_P2_GND")
		)
		(pad "FF5" smd circle
			(at -10.366248 -2.588514)
			(size 0.3048 0.3048)
			(layers "F.Cu" "F.Mask" "F.Paste")
			(net "SMB_RT_CPU0_P2_ROM_MUX_1D_R_SCL")
		)
		(pad "FF8" smd circle
			(at -10.366248 -1.988312)
			(size 0.3048 0.3048)
			(layers "F.Cu" "F.Mask" "F.Paste")
			(net "JTAG_TEST_MODE_RT_CPU0_P2")
		)
		(pad "FF11" smd circle
			(at -10.366248 -1.388364)
			(size 0.3048 0.3048)
			(layers "F.Cu" "F.Mask" "F.Paste")
			(net "RST_RT_CPU0_P2_RESET_N")
		)
		(pad "FF14" smd circle
			(at -10.366248 -0.788416)
			(size 0.3048 0.3048)
			(layers "F.Cu" "F.Mask" "F.Paste")
			(net "GND")
		)
		(pad "FF18" smd circle
			(at -10.366248 -0.188468)
			(size 0.3048 0.3048)
			(layers "F.Cu" "F.Mask" "F.Paste")
			(net "CLK_100M_RETIMER_CPU0_P2_DN")
		)
		(pad "FF21" smd circle
			(at -10.366248 0.41148)
			(size 0.3048 0.3048)
			(layers "F.Cu" "F.Mask" "F.Paste")
			(net "GND")
		)
		(pad "FF24" smd circle
			(at -10.366248 1.011682)
			(size 0.3048 0.3048)
			(layers "F.Cu" "F.Mask" "F.Paste")
			(net "TEST0_RT_CPU0_P2")
		)
		(pad "FF27" smd circle
			(at -10.366248 1.61163)
			(size 0.3048 0.3048)
			(layers "F.Cu" "F.Mask" "F.Paste")
			(net "TEST1_RT_CPU0_P2")
		)
		(pad "FF30" smd circle
			(at -10.366248 2.211578)
			(size 0.3048 0.3048)
			(layers "F.Cu" "F.Mask" "F.Paste")
			(net "TEST2_RT_CPU0_P2")
		)
		(pad "FF33" smd circle
			(at -10.366248 2.811526)
			(size 0.3048 0.3048)
			(layers "F.Cu" "F.Mask" "F.Paste")
			(net "RT_CPU0_P2_SCAN_MODE")
		)
		(pad "FG1" smd oval
			(at -10.54989 -3.938524)
			(size 0.254 0.3302)
			(layers "F.Cu" "F.Mask" "F.Paste")
			(net "NCF_CPU0_P2_GND")
		)
		(pad "FG35" smd oval
			(at -10.54989 3.940048)
			(size 0.254 0.3302)
			(layers "F.Cu" "F.Mask" "F.Paste")
			(net "NCF_CPU0_P2_GND")
		)
		(pad "FH2" smd circle
			(at -10.850118 -3.41884)
			(size 0.3048 0.3048)
			(layers "F.Cu" "F.Mask" "F.Paste")
			(net "NCF_CPU0_P2_GND")
		)
		(pad "FH34" smd circle
			(at -10.850118 3.420364)
			(size 0.3048 0.3048)
			(layers "F.Cu" "F.Mask" "F.Paste")
			(net "NCF_CPU0_P2_GND")
		)
		(pad "FJ3" smd oval
			(at -10.885932 -2.888488 90)
			(size 0.254 0.3302)
			(layers "F.Cu" "F.Mask" "F.Paste")
			(net "SMB_RT_CPU0_P2_ROM_MUX_1D_R_SDA")
		)
		(pad "FJ6" smd oval
			(at -10.885932 -2.288286 90)
			(size 0.254 0.3302)
			(layers "F.Cu" "F.Mask" "F.Paste")
			(net "Net_2208")
		)
		(pad "FJ9" smd oval
			(at -10.885932 -1.688338 90)
			(size 0.254 0.3302)
			(layers "F.Cu" "F.Mask" "F.Paste")
			(net "MODE_RT_CPU0_P2")
		)
		(pad "FJ12" smd oval
			(at -10.885932 -1.08839 90)
			(size 0.254 0.3302)
			(layers "F.Cu" "F.Mask" "F.Paste")
			(net "GND")
		)
		(pad "FJ16" smd oval
			(at -10.885932 -0.488442 90)
			(size 0.254 0.3302)
			(layers "F.Cu" "F.Mask" "F.Paste")
			(net "CLK_100M_RETIMER_CPU0_P2_DP")
		)
		(pad "FJ19" smd oval
			(at -10.885932 0.111506 90)
			(size 0.254 0.3302)
			(layers "F.Cu" "F.Mask" "F.Paste")
			(net "GND")
		)
		(pad "FJ23" smd oval
			(at -10.885932 0.711708 90)
			(size 0.254 0.3302)
			(layers "F.Cu" "F.Mask" "F.Paste")
			(net "Net_2209")
		)
		(pad "FJ25" smd oval
			(at -10.885932 1.311656 90)
			(size 0.254 0.3302)
			(layers "F.Cu" "F.Mask" "F.Paste")
			(net "GPIO2_RT_CPU0_P2")
		)
		(pad "FJ28" smd oval
			(at -10.885932 1.911604 90)
			(size 0.254 0.3302)
			(layers "F.Cu" "F.Mask" "F.Paste")
			(net "GPIO3_RT_CPU0_P2")
		)
		(pad "FJ31" smd oval
			(at -10.885932 2.511552 90)
			(size 0.254 0.3302)
			(layers "F.Cu" "F.Mask" "F.Paste")
			(net "Net_52")
		)
		(pad "G1" smd oval
			(at 9.85012 -3.938524)
			(size 0.254 0.3302)
			(layers "F.Cu" "F.Mask" "F.Paste")
			(net "RT_CPU0_P2_VQPS")
		)
		(pad "G35" smd oval
			(at 9.85012 3.940048)
			(size 0.254 0.3302)
			(layers "F.Cu" "F.Mask" "F.Paste")
			(net "CLKREQ_RT_CPU0_P2_N")
		)
		(pad "H12" smd circle
			(at 9.846818 -1.08839)
			(size 0.3048 0.3048)
			(layers "F.Cu" "F.Mask" "F.Paste")
			(net "GND")
		)
		(pad "H16" smd circle
			(at 9.846818 -0.488442)
			(size 0.3048 0.3048)
			(layers "F.Cu" "F.Mask" "F.Paste")
			(net "GND")
		)
		(pad "H19" smd circle
			(at 9.846818 0.111506)
			(size 0.3048 0.3048)
			(layers "F.Cu" "F.Mask" "F.Paste")
			(net "GND")
		)
		(pad "H31" smd circle
			(at 9.846818 2.511552)
			(size 0.3048 0.3048)
			(layers "F.Cu" "F.Mask" "F.Paste")
			(net "GND")
		)
		(pad "J4" smd circle
			(at 9.602724 -2.817368)
			(size 0.381 0.381)
			(layers "F.Cu" "F.Mask" "F.Paste")
			(net "GND")
		)
		(pad "J22" smd circle
			(at 9.602724 0.703834)
			(size 0.3048 0.3048)
			(layers "F.Cu" "F.Mask" "F.Paste")
			(net "GND")
		)
		(pad "K2" smd circle
			(at 9.549892 -3.41884)
			(size 0.3048 0.3048)
			(layers "F.Cu" "F.Mask" "F.Paste")
			(net "GND")
		)
		(pad "K34" smd circle
			(at 9.549892 3.420364)
			(size 0.3048 0.3048)
			(layers "F.Cu" "F.Mask" "F.Paste")
			(net "GND")
		)
		(pad "L1" smd oval
			(at 9.249918 -3.938524)
			(size 0.254 0.3302)
			(layers "F.Cu" "F.Mask" "F.Paste")
			(net "GND")
		)
		(pad "L35" smd oval
			(at 9.249918 3.940048)
			(size 0.254 0.3302)
			(layers "F.Cu" "F.Mask" "F.Paste")
			(net "GND")
		)
		(pad "M7" smd circle
			(at 9.202674 -2.12471)
			(size 0.381 0.381)
			(layers "F.Cu" "F.Mask" "F.Paste")
			(net "P5E_CPU0_P2_TX_BUF_DP<15>")
		)
		(pad "M26" smd circle
			(at 9.202674 1.339342)
			(size 0.381 0.381)
			(layers "F.Cu" "F.Mask" "F.Paste")
			(net "P5E_CPU0_P2_RX_DP<15>")
		)
		(pad "N2" smd circle
			(at 8.949944 -3.41884)
			(size 0.3048 0.3048)
			(layers "F.Cu" "F.Mask" "F.Paste")
			(net "P5E_CPU0_P2_RX_BUF_DN<15>")
		)
		(pad "N34" smd circle
			(at 8.949944 3.420364)
			(size 0.3048 0.3048)
			(layers "F.Cu" "F.Mask" "F.Paste")
			(net "P5E_CPU0_P2_TX_C_DN<15>")
		)
	)
)
